(kicad_pcb
	(version 20260206)
	(generator "pcbnew")
	(generator_version "10.0")
	(general
		(thickness 1.6)
		(legacy_teardrops no)
	)
	(paper "A4")
	(title_block
		(title "12092022_DA0F0TMDCD0_F0T_Management_Board_D_brd_V3_OCP.brd")
		(comment 1 "Grand Teton / footprints 558-562 of 1440")
	)
	(layers
		(0 "F.Cu" signal "TOP")
		(4 "In1.Cu" signal "GND")
		(6 "In2.Cu" signal "IN1")
		(8 "In3.Cu" signal "GND1")
		(10 "In4.Cu" signal "IN2")
		(12 "In5.Cu" signal "VCC")
		(14 "In6.Cu" signal "VCC1")
		(16 "In7.Cu" signal "IN3")
		(18 "In8.Cu" signal "GND2")
		(20 "In9.Cu" signal "IN4")
		(22 "In10.Cu" signal "GND3")
		(2 "B.Cu" signal "BOTTOM")
		(9 "F.Adhes" user "F.Adhesive")
		(11 "B.Adhes" user "B.Adhesive")
		(13 "F.Paste" user "Package Geometry/Pastemask Top")
		(15 "B.Paste" user "Package Geometry/Pastemask Bottom")
		(5 "F.SilkS" user "Ref Des/Silkscreen Top")
		(7 "B.SilkS" user "Ref Des/Silkscreen Bottom")
		(1 "F.Mask" user "Board Geometry/Soldermask Top")
		(3 "B.Mask" user "Board Geometry/Soldermask Bottom")
		(17 "Dwgs.User" user "User.Drawings")
		(19 "Cmts.User" user "User.Comments")
		(21 "Eco1.User" user "User.Eco1")
		(23 "Eco2.User" user "User.Eco2")
		(25 "Edge.Cuts" user "Board Geometry/Outline")
		(27 "Margin" user)
		(31 "F.CrtYd" user "Package Geometry/Place Bound Top")
		(29 "B.CrtYd" user "Package Geometry/Place Bound Bottom")
		(35 "F.Fab" user "Ref Des/Assembly Top")
		(33 "B.Fab" user "Ref Des/Assembly Bottom")
	)
	(footprint ""
		(layer "F.Cu")
		(at 36.668456 -55.936388 180)
		(property "Reference" "U41"
			(at 6.534912 -0.325628 0)
			(unlocked yes)
			(layer "F.SilkS")
			(effects
				(font
					(size 0.7874 0.5842)
					(thickness 0.1524)
				)
				(justify left)
			)
		)
		(property "Value" ""
			(at 0 0 180)
			(layer "F.Fab")
			(effects
				(font
					(size 1.27 1.27)
				)
			)
		)
		(duplicate_pad_numbers_are_jumpers no)
		(fp_line
			(start 1.525016 1.525016)
			(end 1.525016 1.3208)
			(stroke
				(width 0.1524)
				(type default)
			)
			(layer "F.SilkS")
		)
		(fp_line
			(start 1.525016 1.525016)
			(end -1.525016 1.525016)
			(stroke
				(width 0.1524)
				(type default)
			)
			(layer "F.SilkS")
		)
		(fp_line
			(start 1.525016 -1.3208)
			(end 1.525016 -1.525016)
			(stroke
				(width 0.1524)
				(type default)
			)
			(layer "F.SilkS")
		)
		(fp_line
			(start 1.525016 -1.525016)
			(end 0.9398 -1.525016)
			(stroke
				(width 0.1524)
				(type default)
			)
			(layer "F.SilkS")
		)
		(fp_line
			(start 1.525016 -1.525016)
			(end -1.525016 -1.525016)
			(stroke
				(width 0.1524)
				(type default)
			)
			(layer "F.SilkS")
		)
		(fp_line
			(start 0.9906 1.525016)
			(end 1.525016 1.525016)
			(stroke
				(width 0.1524)
				(type default)
			)
			(layer "F.SilkS")
		)
		(fp_line
			(start -0.8636 -1.525016)
			(end -1.525016 -1.525016)
			(stroke
				(width 0.1524)
				(type default)
			)
			(layer "F.SilkS")
		)
		(fp_line
			(start -1.525016 1.525016)
			(end -0.889 1.525016)
			(stroke
				(width 0.1524)
				(type default)
			)
			(layer "F.SilkS")
		)
		(fp_line
			(start -1.525016 1.3208)
			(end -1.525016 1.525016)
			(stroke
				(width 0.1524)
				(type default)
			)
			(layer "F.SilkS")
		)
		(fp_line
			(start -1.525016 -1.525016)
			(end -1.525016 -1.3208)
			(stroke
				(width 0.1524)
				(type default)
			)
			(layer "F.SilkS")
		)
		(fp_poly
			(pts
				(xy -2.102104 -1.112774) (xy -2.29235 -2.042414) (xy -2.812034 -1.74244)
			)
			(stroke
				(width 0)
				(type default)
			)
			(fill yes)
			(layer "F.SilkS")
		)
		(fp_line
			(start 1.525016 1.525016)
			(end -1.525016 1.525016)
			(stroke
				(width 0.1)
				(type default)
			)
			(layer "F.Fab")
		)
		(fp_line
			(start 1.525016 -1.525016)
			(end 1.525016 1.525016)
			(stroke
				(width 0.1)
				(type default)
			)
			(layer "F.Fab")
		)
		(fp_line
			(start -1.525016 1.525016)
			(end -1.525016 -1.525016)
			(stroke
				(width 0.1)
				(type default)
			)
			(layer "F.Fab")
		)
		(fp_line
			(start -1.525016 -1.525016)
			(end 1.525016 -1.525016)
			(stroke
				(width 0.1)
				(type default)
			)
			(layer "F.Fab")
		)
		(fp_poly
			(pts
				(xy -2.0701 -0.999998) (xy -2.977896 -1.302512) (xy -2.977896 -0.697484)
			)
			(stroke
				(width 0)
				(type default)
			)
			(fill yes)
			(layer "F.Fab")
		)
		(pad "1" smd rect
			(at -1.550162 -0.999998 90)
			(size 0.2794 0.9144)
			(layers "F.Cu" "F.Mask" "F.Paste")
			(net "P1V8_AUX")
		)
		(pad "2" smd rect
			(at -1.550162 -0.500126 90)
			(size 0.2794 0.9144)
			(layers "F.Cu" "F.Mask" "F.Paste")
			(net "P1V8_AUX")
		)
		(pad "3" smd rect
			(at -1.550162 0 90)
			(size 0.2794 0.9144)
			(layers "F.Cu" "F.Mask" "F.Paste")
			(net "P1V8_AUX")
		)
		(pad "4" smd rect
			(at -1.550162 0.500126 90)
			(size 0.2794 0.9144)
			(layers "F.Cu" "F.Mask" "F.Paste")
			(net "U41_ADJ")
		)
		(pad "5" smd rect
			(at -1.550162 0.999998 270)
			(size 0.2794 0.9144)
			(layers "F.Cu" "F.Mask" "F.Paste")
			(net "PWRGD_P1V8_AUX_R")
		)
		(pad "6" smd rect
			(at 1.550162 0.999998 270)
			(size 0.2794 0.9144)
			(layers "F.Cu" "F.Mask" "F.Paste")
			(net "EN_P1V8_R")
		)
		(pad "7" smd rect
			(at 1.550162 0.500126 90)
			(size 0.2794 0.9144)
			(layers "F.Cu" "F.Mask" "F.Paste")
			(net "P3V3_AUX")
		)
		(pad "8" smd rect
			(at 1.550162 0 90)
			(size 0.2794 0.9144)
			(layers "F.Cu" "F.Mask" "F.Paste")
			(net "P3V3_AUX")
		)
		(pad "9" smd rect
			(at 1.550162 -0.500126 90)
			(size 0.2794 0.9144)
			(layers "F.Cu" "F.Mask" "F.Paste")
			(net "P3V3_AUX")
		)
		(pad "10" smd rect
			(at 1.550162 -0.999998 90)
			(size 0.2794 0.9144)
			(layers "F.Cu" "F.Mask" "F.Paste")
			(net "P5V_AUX")
		)
		(pad "TH" smd rect
			(at 0 0 180)
			(size 1.7526 2.667)
			(layers "F.Cu" "F.Mask" "F.Paste")
			(net "GND")
		)
		(zone
			(layer "F.Cu")
			(hatch none 0.5)
			(connect_pads
				(clearance 0)
			)
			(min_thickness 0.25)
			(keepout
				(tracks not_allowed)
				(vias allowed)
				(pads allowed)
				(copperpour not_allowed)
				(footprints allowed)
			)
			(placement
				(enabled no)
				(sheetname "")
			)
			(fill
				(thermal_gap 0.5)
				(thermal_bridge_width 0.5)
				(island_removal_mode 0)
			)
			(polygon
				(pts
					(xy 37.685218 -54.40299) (xy 37.685218 -57.45099) (xy 35.653218 -57.45099) (xy 35.653218 -54.40299)
					(xy 37.583618 -54.40299) (xy 37.583618 -54.52999) (xy 35.729418 -54.52999) (xy 35.729418 -57.34939)
					(xy 37.609018 -57.34939) (xy 37.609018 -54.40299)
				)
			)
		)
	)
	(footprint ""
		(layer "F.Cu")
		(at 40.132 -70.485 90)
		(property "Reference" "U15"
			(at -1.1684 -1.70053 90)
			(unlocked yes)
			(layer "F.SilkS")
			(effects
				(font
					(size 0.7874 0.5842)
					(thickness 0.1524)
				)
			)
		)
		(property "Value" ""
			(at 0 0 90)
			(layer "F.Fab")
			(effects
				(font
					(size 1.27 1.27)
				)
			)
		)
		(duplicate_pad_numbers_are_jumpers no)
		(fp_line
			(start 1.7018 -1.1176)
			(end 0.254 -1.1176)
			(stroke
				(width 0.1524)
				(type default)
			)
			(layer "F.SilkS")
		)
		(fp_line
			(start 1.7018 -1.1176)
			(end 1.7018 1.1176)
			(stroke
				(width 0.1524)
				(type default)
			)
			(layer "F.SilkS")
		)
		(fp_line
			(start 0.254 -1.1176)
			(end 0 -0.7112)
			(stroke
				(width 0.1524)
				(type default)
			)
			(layer "F.SilkS")
		)
		(fp_line
			(start -0.254 -1.1176)
			(end -1.7018 -1.1176)
			(stroke
				(width 0.1524)
				(type default)
			)
			(layer "F.SilkS")
		)
		(fp_line
			(start 0 -0.7112)
			(end -0.254 -1.1176)
			(stroke
				(width 0.1524)
				(type default)
			)
			(layer "F.SilkS")
		)
		(fp_line
			(start 1.7018 1.1176)
			(end -1.7018 1.1176)
			(stroke
				(width 0.1524)
				(type default)
			)
			(layer "F.SilkS")
		)
		(fp_line
			(start -1.7018 1.1176)
			(end -1.7018 -1.1176)
			(stroke
				(width 0.1524)
				(type default)
			)
			(layer "F.SilkS")
		)
		(fp_poly
			(pts
				(xy -1.8161 -0.675386) (xy -2.4003 -0.446786) (xy -2.4003 -0.878586)
			)
			(stroke
				(width 0)
				(type default)
			)
			(fill yes)
			(layer "F.SilkS")
		)
		(fp_line
			(start 1.5494 -1.1176)
			(end 0.254 -1.1176)
			(stroke
				(width 0.1)
				(type default)
			)
			(layer "F.Fab")
		)
		(fp_line
			(start 1.5494 -1.1176)
			(end 1.5494 1.1176)
			(stroke
				(width 0.1)
				(type default)
			)
			(layer "F.Fab")
		)
		(fp_line
			(start 0.254 -1.1176)
			(end -0.254 -1.1176)
			(stroke
				(width 0.1)
				(type default)
			)
			(layer "F.Fab")
		)
		(fp_line
			(start -0.254 -1.1176)
			(end -1.5494 -1.1176)
			(stroke
				(width 0.1)
				(type default)
			)
			(layer "F.Fab")
		)
		(fp_line
			(start 1.5494 1.1176)
			(end -1.5494 1.1176)
			(stroke
				(width 0.1)
				(type default)
			)
			(layer "F.Fab")
		)
		(fp_line
			(start -1.5494 1.1176)
			(end -1.5494 -1.1176)
			(stroke
				(width 0.1)
				(type default)
			)
			(layer "F.Fab")
		)
		(fp_poly
			(pts
				(xy -1.8161 -0.675386) (xy -2.4003 -0.446786) (xy -2.4003 -0.878586)
			)
			(stroke
				(width 0)
				(type default)
			)
			(fill yes)
			(layer "F.Fab")
		)
		(pad "1" smd rect
			(at -0.962406 -0.649986)
			(size 0.3302 1.1684)
			(layers "F.Cu" "F.Mask" "F.Paste")
			(net "SYS_BMC_PWRBTN_R_N")
		)
		(pad "2" smd rect
			(at -0.962406 0)
			(size 0.3302 1.1684)
			(layers "F.Cu" "F.Mask" "F.Paste")
			(net "PWR_BTN_BMC_N")
		)
		(pad "3" smd rect
			(at -0.962406 0.649986)
			(size 0.3302 1.1684)
			(layers "F.Cu" "F.Mask" "F.Paste")
			(net "GND")
		)
		(pad "4" smd rect
			(at 0.962406 0.649986)
			(size 0.3302 1.1684)
			(layers "F.Cu" "F.Mask" "F.Paste")
			(net "SYS_PWRBTN_N")
		)
		(pad "5" smd rect
			(at 0.962406 -0.649986)
			(size 0.3302 1.1684)
			(layers "F.Cu" "F.Mask" "F.Paste")
			(net "P3V3_AUX")
		)
	)
	(footprint ""
		(layer "F.Cu")
		(at 19.685 -56.1848 90)
		(property "Reference" "R901"
			(at 0 0 90)
			(layer "F.SilkS")
			(hide yes)
			(effects
				(font
					(size 1.27 1.27)
				)
			)
		)
		(property "Value" ""
			(at 0 0 90)
			(layer "F.Fab")
			(effects
				(font
					(size 1.27 1.27)
				)
			)
		)
		(duplicate_pad_numbers_are_jumpers no)
		(fp_line
			(start 0.7874 -0.4064)
			(end 0.7874 0.4064)
			(stroke
				(width 0.1524)
				(type default)
			)
			(layer "F.SilkS")
		)
		(fp_line
			(start -0.7874 -0.4064)
			(end 0.7874 -0.4064)
			(stroke
				(width 0.1524)
				(type default)
			)
			(layer "F.SilkS")
		)
		(fp_line
			(start 0.7874 0.4064)
			(end -0.7874 0.4064)
			(stroke
				(width 0.1524)
				(type default)
			)
			(layer "F.SilkS")
		)
		(fp_line
			(start -0.7874 0.4064)
			(end -0.7874 -0.4064)
			(stroke
				(width 0.1524)
				(type default)
			)
			(layer "F.SilkS")
		)
		(fp_line
			(start -0.12065 -0.305054)
			(end -0.12065 -0.2794)
			(stroke
				(width 0.1)
				(type default)
			)
			(layer "F.Fab")
		)
		(fp_line
			(start -0.67945 -0.305054)
			(end -0.12065 -0.305054)
			(stroke
				(width 0.1)
				(type default)
			)
			(layer "F.Fab")
		)
		(fp_line
			(start 0.67945 -0.3048)
			(end 0.67945 0.3048)
			(stroke
				(width 0.1)
				(type default)
			)
			(layer "F.Fab")
		)
		(fp_line
			(start 0.12065 -0.3048)
			(end 0.67945 -0.3048)
			(stroke
				(width 0.1)
				(type default)
			)
			(layer "F.Fab")
		)
		(fp_line
			(start 0.12065 -0.2794)
			(end 0.12065 -0.3048)
			(stroke
				(width 0.1)
				(type default)
			)
			(layer "F.Fab")
		)
		(fp_line
			(start -0.12065 -0.2794)
			(end 0.12065 -0.2794)
			(stroke
				(width 0.1)
				(type default)
			)
			(layer "F.Fab")
		)
		(fp_line
			(start 0.120396 0.2794)
			(end -0.12065 0.2794)
			(stroke
				(width 0.1)
				(type default)
			)
			(layer "F.Fab")
		)
		(fp_line
			(start -0.12065 0.2794)
			(end -0.12065 0.3048)
			(stroke
				(width 0.1)
				(type default)
			)
			(layer "F.Fab")
		)
		(fp_line
			(start 0.67945 0.3048)
			(end 0.120396 0.3048)
			(stroke
				(width 0.1)
				(type default)
			)
			(layer "F.Fab")
		)
		(fp_line
			(start 0.120396 0.3048)
			(end 0.120396 0.2794)
			(stroke
				(width 0.1)
				(type default)
			)
			(layer "F.Fab")
		)
		(fp_line
			(start -0.12065 0.3048)
			(end -0.67945 0.3048)
			(stroke
				(width 0.1)
				(type default)
			)
			(layer "F.Fab")
		)
		(fp_line
			(start -0.67945 0.3048)
			(end -0.67945 -0.305054)
			(stroke
				(width 0.1)
				(type default)
			)
			(layer "F.Fab")
		)
		(pad "1" smd circle
			(at -0.40005 0 90)
			(size 0 0)
			(layers "F.Cu" "F.Mask" "F.Paste")
			(net "UART_6_BMC_RXD")
		)
		(pad "2" smd circle
			(at 0.40005 0 90)
			(size 0 0)
			(layers "F.Cu" "F.Mask" "F.Paste")
			(net "UART_6_BMC_RXD_R")
		)
	)
	(footprint ""
		(layer "F.Cu")
		(at 70.619112 -35.258756 90)
		(property "Reference" "C114"
			(at 0 0 90)
			(layer "F.SilkS")
			(hide yes)
			(effects
				(font
					(size 1.27 1.27)
				)
			)
		)
		(property "Value" ""
			(at 0 0 90)
			(layer "F.Fab")
			(effects
				(font
					(size 1.27 1.27)
				)
			)
		)
		(duplicate_pad_numbers_are_jumpers no)
		(fp_line
			(start 0.7874 -0.4064)
			(end 0.7874 0.4064)
			(stroke
				(width 0.1524)
				(type default)
			)
			(layer "F.SilkS")
		)
		(fp_line
			(start -0.7874 -0.4064)
			(end 0.7874 -0.4064)
			(stroke
				(width 0.1524)
				(type default)
			)
			(layer "F.SilkS")
		)
		(fp_line
			(start 0.7874 0.4064)
			(end -0.7874 0.4064)
			(stroke
				(width 0.1524)
				(type default)
			)
			(layer "F.SilkS")
		)
		(fp_line
			(start -0.7874 0.4064)
			(end -0.7874 -0.4064)
			(stroke
				(width 0.1524)
				(type default)
			)
			(layer "F.SilkS")
		)
		(fp_line
			(start -0.12065 -0.305054)
			(end -0.12065 -0.2794)
			(stroke
				(width 0.1)
				(type default)
			)
			(layer "F.Fab")
		)
		(fp_line
			(start -0.67945 -0.305054)
			(end -0.12065 -0.305054)
			(stroke
				(width 0.1)
				(type default)
			)
			(layer "F.Fab")
		)
		(fp_line
			(start 0.67945 -0.3048)
			(end 0.67945 0.3048)
			(stroke
				(width 0.1)
				(type default)
			)
			(layer "F.Fab")
		)
		(fp_line
			(start 0.12065 -0.3048)
			(end 0.67945 -0.3048)
			(stroke
				(width 0.1)
				(type default)
			)
			(layer "F.Fab")
		)
		(fp_line
			(start 0.12065 -0.2794)
			(end 0.12065 -0.3048)
			(stroke
				(width 0.1)
				(type default)
			)
			(layer "F.Fab")
		)
		(fp_line
			(start -0.12065 -0.2794)
			(end 0.12065 -0.2794)
			(stroke
				(width 0.1)
				(type default)
			)
			(layer "F.Fab")
		)
		(fp_line
			(start 0.120396 0.2794)
			(end -0.12065 0.2794)
			(stroke
				(width 0.1)
				(type default)
			)
			(layer "F.Fab")
		)
		(fp_line
			(start -0.12065 0.2794)
			(end -0.12065 0.3048)
			(stroke
				(width 0.1)
				(type default)
			)
			(layer "F.Fab")
		)
		(fp_line
			(start 0.67945 0.3048)
			(end 0.120396 0.3048)
			(stroke
				(width 0.1)
				(type default)
			)
			(layer "F.Fab")
		)
		(fp_line
			(start 0.120396 0.3048)
			(end 0.120396 0.2794)
			(stroke
				(width 0.1)
				(type default)
			)
			(layer "F.Fab")
		)
		(fp_line
			(start -0.12065 0.3048)
			(end -0.67945 0.3048)
			(stroke
				(width 0.1)
				(type default)
			)
			(layer "F.Fab")
		)
		(fp_line
			(start -0.67945 0.3048)
			(end -0.67945 -0.305054)
			(stroke
				(width 0.1)
				(type default)
			)
			(layer "F.Fab")
		)
		(pad "1" smd circle
			(at -0.40005 0 90)
			(size 0 0)
			(layers "F.Cu" "F.Mask" "F.Paste")
			(net "P1V8_AUX")
		)
		(pad "2" smd circle
			(at 0.40005 0 90)
			(size 0 0)
			(layers "F.Cu" "F.Mask" "F.Paste")
			(net "GND")
		)
	)
	(footprint ""
		(layer "F.Cu")
		(at 29.27604 -68.504054 90)
		(property "Reference" "R662"
			(at 0 0 90)
			(layer "F.SilkS")
			(hide yes)
			(effects
				(font
					(size 1.27 1.27)
				)
			)
		)
		(property "Value" ""
			(at 0 0 90)
			(layer "F.Fab")
			(effects
				(font
					(size 1.27 1.27)
				)
			)
		)
		(duplicate_pad_numbers_are_jumpers no)
		(fp_line
			(start 0.7874 -0.4064)
			(end 0.7874 0.4064)
			(stroke
				(width 0.1524)
				(type default)
			)
			(layer "F.SilkS")
		)
		(fp_line
			(start -0.7874 -0.4064)
			(end 0.7874 -0.4064)
			(stroke
				(width 0.1524)
				(type default)
			)
			(layer "F.SilkS")
		)
		(fp_line
			(start 0.7874 0.4064)
			(end -0.7874 0.4064)
			(stroke
				(width 0.1524)
				(type default)
			)
			(layer "F.SilkS")
		)
		(fp_line
			(start -0.7874 0.4064)
			(end -0.7874 -0.4064)
			(stroke
				(width 0.1524)
				(type default)
			)
			(layer "F.SilkS")
		)
		(fp_line
			(start -0.12065 -0.305054)
			(end -0.12065 -0.2794)
			(stroke
				(width 0.1)
				(type default)
			)
			(layer "F.Fab")
		)
		(fp_line
			(start -0.67945 -0.305054)
			(end -0.12065 -0.305054)
			(stroke
				(width 0.1)
				(type default)
			)
			(layer "F.Fab")
		)
		(fp_line
			(start 0.67945 -0.3048)
			(end 0.67945 0.3048)
			(stroke
				(width 0.1)
				(type default)
			)
			(layer "F.Fab")
		)
		(fp_line
			(start 0.12065 -0.3048)
			(end 0.67945 -0.3048)
			(stroke
				(width 0.1)
				(type default)
			)
			(layer "F.Fab")
		)
		(fp_line
			(start 0.12065 -0.2794)
			(end 0.12065 -0.3048)
			(stroke
				(width 0.1)
				(type default)
			)
			(layer "F.Fab")
		)
		(fp_line
			(start -0.12065 -0.2794)
			(end 0.12065 -0.2794)
			(stroke
				(width 0.1)
				(type default)
			)
			(layer "F.Fab")
		)
		(fp_line
			(start 0.120396 0.2794)
			(end -0.12065 0.2794)
			(stroke
				(width 0.1)
				(type default)
			)
			(layer "F.Fab")
		)
		(fp_line
			(start -0.12065 0.2794)
			(end -0.12065 0.3048)
			(stroke
				(width 0.1)
				(type default)
			)
			(layer "F.Fab")
		)
		(fp_line
			(start 0.67945 0.3048)
			(end 0.120396 0.3048)
			(stroke
				(width 0.1)
				(type default)
			)
			(layer "F.Fab")
		)
		(fp_line
			(start 0.120396 0.3048)
			(end 0.120396 0.2794)
			(stroke
				(width 0.1)
				(type default)
			)
			(layer "F.Fab")
		)
		(fp_line
			(start -0.12065 0.3048)
			(end -0.67945 0.3048)
			(stroke
				(width 0.1)
				(type default)
			)
			(layer "F.Fab")
		)
		(fp_line
			(start -0.67945 0.3048)
			(end -0.67945 -0.305054)
			(stroke
				(width 0.1)
				(type default)
			)
			(layer "F.Fab")
		)
		(pad "1" smd circle
			(at -0.40005 0 90)
			(size 0 0)
			(layers "F.Cu" "F.Mask" "F.Paste")
			(net "P3V3_AUX")
		)
		(pad "2" smd circle
			(at 0.40005 0 90)
			(size 0 0)
			(layers "F.Cu" "F.Mask" "F.Paste")
			(net "EMMC_DT7_R")
		)
	)
)
